# SCM (Grand Teton) — schematic netlist excerpt (pin names and nets, part order shuffled) for the footprints in the layout excerpt that follows; sources: Cadence DE-HDL packaged netlist, KiCad conversion of 12092022_DA0F0TMDCD0_F0T_Management_Board_D_brd_V3_OCP.brd

C33  Q_CAP  0.1UF 25V 10% X7R  pkg 0402  page 13 : A = P3V3_P2V5_P1V8_RVDD ; B = GND
R750  Q_RES  33.2 1% CHIP  pkg 0402LF  page 36 : A = FM_BMC_DEBUG_SW_N ; B = FM_BMC_DEBUG_SW_R2_N

(kicad_pcb
	(version 20260206)
	(generator "pcbnew")
	(generator_version "10.0")
	(general
		(thickness 1.6)
		(legacy_teardrops no)
	)
	(paper "A4")
	(title_block
		(title "12092022_DA0F0TMDCD0_F0T_Management_Board_D_brd_V3_OCP.brd")
		(comment 1 "Grand Teton / footprints 895-896 of 1440")
	)
	(layers
		(0 "F.Cu" signal "TOP")
		(4 "In1.Cu" signal "GND")
		(6 "In2.Cu" signal "IN1")
		(8 "In3.Cu" signal "GND1")
		(10 "In4.Cu" signal "IN2")
		(12 "In5.Cu" signal "VCC")
		(14 "In6.Cu" signal "VCC1")
		(16 "In7.Cu" signal "IN3")
		(18 "In8.Cu" signal "GND2")
		(20 "In9.Cu" signal "IN4")
		(22 "In10.Cu" signal "GND3")
		(2 "B.Cu" signal "BOTTOM")
		(9 "F.Adhes" user "F.Adhesive")
		(11 "B.Adhes" user "B.Adhesive")
		(13 "F.Paste" user "Package Geometry/Pastemask Top")
		(15 "B.Paste" user "Package Geometry/Pastemask Bottom")
		(5 "F.SilkS" user "Ref Des/Silkscreen Top")
		(7 "B.SilkS" user "Ref Des/Silkscreen Bottom")
		(1 "F.Mask" user "Board Geometry/Soldermask Top")
		(3 "B.Mask" user "Board Geometry/Soldermask Bottom")
		(17 "Dwgs.User" user "User.Drawings")
		(19 "Cmts.User" user "User.Comments")
		(21 "Eco1.User" user "User.Eco1")
		(23 "Eco2.User" user "User.Eco2")
		(25 "Edge.Cuts" user "Board Geometry/Outline")
		(27 "Margin" user)
		(31 "F.CrtYd" user "Package Geometry/Place Bound Top")
		(29 "B.CrtYd" user "Package Geometry/Place Bound Bottom")
		(35 "F.Fab" user "Ref Des/Assembly Top")
		(33 "B.Fab" user "Ref Des/Assembly Bottom")
	)
	(footprint ""
		(layer "B.Cu")
		(at 21.971 -101.981 90)
		(property "Reference" "R750"
			(at 0 0 90)
			(layer "B.SilkS")
			(hide yes)
			(effects
				(font
					(size 1.27 1.27)
				)
				(justify mirror)
			)
		)
		(property "Value" ""
			(at 0 0 90)
			(layer "B.Fab")
			(effects
				(font
					(size 1.27 1.27)
				)
				(justify mirror)
			)
		)
		(duplicate_pad_numbers_are_jumpers no)
		(fp_line
			(start 0.7874 -0.4064)
			(end -0.7874 -0.4064)
			(stroke
				(width 0.1524)
				(type default)
			)
			(layer "B.SilkS")
		)
		(fp_line
			(start -0.7874 -0.4064)
			(end -0.7874 0.4064)
			(stroke
				(width 0.1524)
				(type default)
			)
			(layer "B.SilkS")
		)
		(fp_line
			(start 0.7874 0.4064)
			(end 0.7874 -0.4064)
			(stroke
				(width 0.1524)
				(type default)
			)
			(layer "B.SilkS")
		)
		(fp_line
			(start -0.7874 0.4064)
			(end 0.7874 0.4064)
			(stroke
				(width 0.1524)
				(type default)
			)
			(layer "B.SilkS")
		)
		(fp_line
			(start 0.67945 -0.305054)
			(end 0.12065 -0.305054)
			(stroke
				(width 0.1)
				(type default)
			)
			(layer "B.Fab")
		)
		(fp_line
			(start 0.12065 -0.305054)
			(end 0.12065 -0.2794)
			(stroke
				(width 0.1)
				(type default)
			)
			(layer "B.Fab")
		)
		(fp_line
			(start -0.12065 -0.3048)
			(end -0.67945 -0.3048)
			(stroke
				(width 0.1)
				(type default)
			)
			(layer "B.Fab")
		)
		(fp_line
			(start -0.67945 -0.3048)
			(end -0.67945 0.3048)
			(stroke
				(width 0.1)
				(type default)
			)
			(layer "B.Fab")
		)
		(fp_line
			(start 0.12065 -0.2794)
			(end -0.12065 -0.2794)
			(stroke
				(width 0.1)
				(type default)
			)
			(layer "B.Fab")
		)
		(fp_line
			(start -0.12065 -0.2794)
			(end -0.12065 -0.3048)
			(stroke
				(width 0.1)
				(type default)
			)
			(layer "B.Fab")
		)
		(fp_line
			(start 0.12065 0.2794)
			(end 0.12065 0.3048)
			(stroke
				(width 0.1)
				(type default)
			)
			(layer "B.Fab")
		)
		(fp_line
			(start -0.120396 0.2794)
			(end 0.12065 0.2794)
			(stroke
				(width 0.1)
				(type default)
			)
			(layer "B.Fab")
		)
		(fp_line
			(start 0.67945 0.3048)
			(end 0.67945 -0.305054)
			(stroke
				(width 0.1)
				(type default)
			)
			(layer "B.Fab")
		)
		(fp_line
			(start 0.12065 0.3048)
			(end 0.67945 0.3048)
			(stroke
				(width 0.1)
				(type default)
			)
			(layer "B.Fab")
		)
		(fp_line
			(start -0.120396 0.3048)
			(end -0.120396 0.2794)
			(stroke
				(width 0.1)
				(type default)
			)
			(layer "B.Fab")
		)
		(fp_line
			(start -0.67945 0.3048)
			(end -0.120396 0.3048)
			(stroke
				(width 0.1)
				(type default)
			)
			(layer "B.Fab")
		)
		(pad "1" smd circle
			(at 0.40005 0 270)
			(size 0 0)
			(layers "B.Cu" "B.Mask" "B.Paste")
			(net "FM_BMC_DEBUG_SW_N")
		)
		(pad "2" smd circle
			(at -0.40005 0 270)
			(size 0 0)
			(layers "B.Cu" "B.Mask" "B.Paste")
			(net "FM_BMC_DEBUG_SW_R2_N")
		)
	)
	(footprint ""
		(layer "B.Cu")
		(at 49.109122 -45.716444 90)
		(property "Reference" "C33"
			(at 0 0 90)
			(layer "B.SilkS")
			(hide yes)
			(effects
				(font
					(size 1.27 1.27)
				)
				(justify mirror)
			)
		)
		(property "Value" ""
			(at 0 0 90)
			(layer "B.Fab")
			(effects
				(font
					(size 1.27 1.27)
				)
				(justify mirror)
			)
		)
		(duplicate_pad_numbers_are_jumpers no)
		(fp_line
			(start 0.7874 -0.4064)
			(end -0.7874 -0.4064)
			(stroke
				(width 0.1524)
				(type default)
			)
			(layer "B.SilkS")
		)
		(fp_line
			(start -0.7874 -0.4064)
			(end -0.7874 0.4064)
			(stroke
				(width 0.1524)
				(type default)
			)
			(layer "B.SilkS")
		)
		(fp_line
			(start 0.7874 0.4064)
			(end 0.7874 -0.4064)
			(stroke
				(width 0.1524)
				(type default)
			)
			(layer "B.SilkS")
		)
		(fp_line
			(start -0.7874 0.4064)
			(end 0.7874 0.4064)
			(stroke
				(width 0.1524)
				(type default)
			)
			(layer "B.SilkS")
		)
		(fp_line
			(start 0.67945 -0.305054)
			(end 0.12065 -0.305054)
			(stroke
				(width 0.1)
				(type default)
			)
			(layer "B.Fab")
		)
		(fp_line
			(start 0.12065 -0.305054)
			(end 0.12065 -0.2794)
			(stroke
				(width 0.1)
				(type default)
			)
			(layer "B.Fab")
		)
		(fp_line
			(start -0.12065 -0.3048)
			(end -0.67945 -0.3048)
			(stroke
				(width 0.1)
				(type default)
			)
			(layer "B.Fab")
		)
		(fp_line
			(start -0.67945 -0.3048)
			(end -0.67945 0.3048)
			(stroke
				(width 0.1)
				(type default)
			)
			(layer "B.Fab")
		)
		(fp_line
			(start 0.12065 -0.2794)
			(end -0.12065 -0.2794)
			(stroke
				(width 0.1)
				(type default)
			)
			(layer "B.Fab")
		)
		(fp_line
			(start -0.12065 -0.2794)
			(end -0.12065 -0.3048)
			(stroke
				(width 0.1)
				(type default)
			)
			(layer "B.Fab")
		)
		(fp_line
			(start 0.12065 0.2794)
			(end 0.12065 0.3048)
			(stroke
				(width 0.1)
				(type default)
			)
			(layer "B.Fab")
		)
		(fp_line
			(start -0.120396 0.2794)
			(end 0.12065 0.2794)
			(stroke
				(width 0.1)
				(type default)
			)
			(layer "B.Fab")
		)
		(fp_line
			(start 0.67945 0.3048)
			(end 0.67945 -0.305054)
			(stroke
				(width 0.1)
				(type default)
			)
			(layer "B.Fab")
		)
		(fp_line
			(start 0.12065 0.3048)
			(end 0.67945 0.3048)
			(stroke
				(width 0.1)
				(type default)
			)
			(layer "B.Fab")
		)
		(fp_line
			(start -0.120396 0.3048)
			(end -0.120396 0.2794)
			(stroke
				(width 0.1)
				(type default)
			)
			(layer "B.Fab")
		)
		(fp_line
			(start -0.67945 0.3048)
			(end -0.120396 0.3048)
			(stroke
				(width 0.1)
				(type default)
			)
			(layer "B.Fab")
		)
		(pad "1" smd circle
			(at 0.40005 0 270)
			(size 0 0)
			(layers "B.Cu" "B.Mask" "B.Paste")
			(net "P3V3_P2V5_P1V8_RVDD")
		)
		(pad "2" smd circle
			(at -0.40005 0 270)
			(size 0 0)
			(layers "B.Cu" "B.Mask" "B.Paste")
			(net "GND")
		)
	)
)
